#ISCELL
  mstr_misc dns *
  *
#ISCELL
  pure_quanta quanta_title_block_c *
  *
#ISCELL
  standard offpage *
  page198_i1
#CELL
  pure_quanta q_res *
  page198_i10
#CELL
  pure_quanta q_res *
  page198_i11
#CELL
  pure_quanta q_res *
  page198_i12
#ISCELL
  standard offpage *
  page198_i13
#ISCELL
  standard offpage *
  page198_i14
#ISCELL
  standard offpage *
  page198_i15
#ISCELL
  standard offpage *
  page198_i16
#ISCELL
  standard offpage *
  page198_i17
#ISCELL
  standard offpage *
  page198_i18
#CELL
  pure_quanta q_res *
  page198_i19
#ISCELL
  standard offpage *
  page198_i2
#CELL
  pure_quanta q_res *
  page198_i20
#CELL
  pure_quanta q_res *
  page198_i21
#CELL
  pure_quanta q_res *
  page198_i22
#CELL
  pure_quanta q_res *
  page198_i23
#CELL
  pure_quanta q_res *
  page198_i24
#ISCELL
  standard offpage *
  page198_i25
#ISCELL
  standard offpage *
  page198_i26
#CELL
  pure_quanta q_res *
  page198_i27
#CELL
  pure_quanta q_res *
  page198_i28
#CELL
  pure_quanta q_res *
  page198_i29
#ISCELL
  standard offpage *
  page198_i3
#CELL
  pure_quanta q_res *
  page198_i30
#ISCELL
  standard offpage *
  page198_i31
#ISCELL
  standard offpage *
  page198_i32
#ISCELL
  standard offpage *
  page198_i33
#ISCELL
  standard offpage *
  page198_i34
#ISCELL
  standard offpage *
  page198_i35
#ISCELL
  standard offpage *
  page198_i36
#ISCELL
  standard offpage *
  page198_i37
#ISCELL
  standard offpage *
  page198_i38
#ISCELL
  standard offpage *
  page198_i39
#ISCELL
  standard offpage *
  page198_i4
#ISCELL
  standard offpage *
  page198_i40
#ISCELL
  standard offpage *
  page198_i41
#ISCELL
  standard offpage *
  page198_i42
#CELL
  pure_quanta q_res *
  page198_i43
#CELL
  pure_quanta q_res *
  page198_i44
#CELL
  pure_quanta q_res *
  page198_i45
#CELL
  pure_quanta q_res *
  page198_i46
#CELL
  pure_quanta q_res *
  page198_i47
#CELL
  pure_quanta q_res *
  page198_i48
#ISCELL
  standard offpage *
  page198_i49
#ISCELL
  standard offpage *
  page198_i5
#ISCELL
  standard offpage *
  page198_i50
#ISCELL
  standard offpage *
  page198_i51
#ISCELL
  standard offpage *
  page198_i52
#ISCELL
  standard offpage *
  page198_i53
#ISCELL
  standard offpage *
  page198_i54
#ISCELL
  standard offpage *
  page198_i55
#ISCELL
  standard offpage *
  page198_i56
#CELL
  pure_quanta q_res *
  page198_i57
#CELL
  pure_quanta q_res *
  page198_i58
#ISCELL
  standard offpage *
  page198_i59
#ISCELL
  standard offpage *
  page198_i6
#ISCELL
  standard offpage *
  page198_i60
#CELL
  pure_quanta q_res *
  page198_i7
#CELL
  pure_quanta q_res *
  page198_i8
#CELL
  pure_quanta q_res *
  page198_i9
